# S9S_MB_2U (Grand Teton) — schematic netlist excerpt (pin names and nets, part order shuffled) for the footprints in the layout excerpt that follows; sources: Cadence DE-HDL packaged netlist, KiCad conversion of 03242023_DA0F0TMBIJ0_F0T_Motherboard_J_brd_V01_OCP.brd

PC71  Q_CAP  22UF 16V 20% X6S  pkg C0805  page 259 : A = SW_P3V3_AUX_FLT ; B = GND
R967  Q_RES  1K 1% CHIP  pkg 0402LF  page 235 : A = P3V3_AUX ; B = SMB_PEHPCPU0_LVC3_SDA
PR3338  Q_RES  0 5% CHIP  pkg 0402LF  page 300 : A = P3V3_AUX ; B = PVNN_MAIN_CPU1_VCC

(kicad_pcb
	(version 20260206)
	(generator "pcbnew")
	(generator_version "10.0")
	(general
		(thickness 1.6)
		(legacy_teardrops no)
	)
	(paper "A4")
	(title_block
		(title "03242023_DA0F0TMBIJ0_F0T_Motherboard_J_brd_V01_OCP.brd")
		(comment 1 "Grand Teton / footprints 6084-6086 of 6105")
	)
	(layers
		(0 "F.Cu" signal "TOP")
		(4 "In1.Cu" signal "GND")
		(6 "In2.Cu" signal "IN1")
		(8 "In3.Cu" signal "GND1")
		(10 "In4.Cu" signal "IN2")
		(12 "In5.Cu" signal "GND2")
		(14 "In6.Cu" signal "IN3")
		(16 "In7.Cu" signal "GND3")
		(18 "In8.Cu" signal "VCC")
		(20 "In9.Cu" signal "VCC1")
		(22 "In10.Cu" signal "GND4")
		(24 "In11.Cu" signal "IN4")
		(26 "In12.Cu" signal "GND5")
		(28 "In13.Cu" signal "IN5")
		(30 "In14.Cu" signal "GND6")
		(32 "In15.Cu" signal "IN6")
		(34 "In16.Cu" signal "GND7")
		(2 "B.Cu" signal "BOTTOM")
		(9 "F.Adhes" user "F.Adhesive")
		(11 "B.Adhes" user "B.Adhesive")
		(13 "F.Paste" user "Package Geometry/Pastemask Top")
		(15 "B.Paste" user "Package Geometry/Pastemask Bottom")
		(5 "F.SilkS" user "Ref Des/Silkscreen Top")
		(7 "B.SilkS" user "Ref Des/Silkscreen Bottom")
		(1 "F.Mask" user "Board Geometry/Soldermask Top")
		(3 "B.Mask" user "Board Geometry/Soldermask Bottom")
		(17 "Dwgs.User" user "User.Drawings")
		(19 "Cmts.User" user "User.Comments")
		(21 "Eco1.User" user "User.Eco1")
		(23 "Eco2.User" user "User.Eco2")
		(25 "Edge.Cuts" user "Board Geometry/Outline")
		(27 "Margin" user)
		(31 "F.CrtYd" user "Package Geometry/Place Bound Top")
		(29 "B.CrtYd" user "Package Geometry/Place Bound Bottom")
		(35 "F.Fab" user "Ref Des/Assembly Top")
		(33 "B.Fab" user "Ref Des/Assembly Bottom")
	)
	(footprint ""
		(layer "B.Cu")
		(at 22.219412 -184.31256 180)
		(property "Reference" "PR3338"
			(at 0 0 0)
			(layer "B.SilkS")
			(hide yes)
			(effects
				(font
					(size 1.27 1.27)
				)
				(justify mirror)
			)
		)
		(property "Value" ""
			(at 0 0 0)
			(layer "B.Fab")
			(effects
				(font
					(size 1.27 1.27)
				)
				(justify mirror)
			)
		)
		(duplicate_pad_numbers_are_jumpers no)
		(fp_line
			(start 0.7874 0.4064)
			(end 0.7874 -0.4064)
			(stroke
				(width 0.1524)
				(type default)
			)
			(layer "B.SilkS")
		)
		(fp_line
			(start 0.7874 -0.4064)
			(end -0.7874 -0.4064)
			(stroke
				(width 0.1524)
				(type default)
			)
			(layer "B.SilkS")
		)
		(fp_line
			(start -0.7874 0.4064)
			(end 0.7874 0.4064)
			(stroke
				(width 0.1524)
				(type default)
			)
			(layer "B.SilkS")
		)
		(fp_line
			(start -0.7874 -0.4064)
			(end -0.7874 0.4064)
			(stroke
				(width 0.1524)
				(type default)
			)
			(layer "B.SilkS")
		)
		(fp_line
			(start 0.67945 0.3048)
			(end 0.67945 -0.305054)
			(stroke
				(width 0.1)
				(type default)
			)
			(layer "B.Fab")
		)
		(fp_line
			(start 0.67945 -0.305054)
			(end 0.12065 -0.305054)
			(stroke
				(width 0.1)
				(type default)
			)
			(layer "B.Fab")
		)
		(fp_line
			(start 0.12065 0.3048)
			(end 0.67945 0.3048)
			(stroke
				(width 0.1)
				(type default)
			)
			(layer "B.Fab")
		)
		(fp_line
			(start 0.12065 0.2794)
			(end 0.12065 0.3048)
			(stroke
				(width 0.1)
				(type default)
			)
			(layer "B.Fab")
		)
		(fp_line
			(start 0.12065 -0.2794)
			(end -0.12065 -0.2794)
			(stroke
				(width 0.1)
				(type default)
			)
			(layer "B.Fab")
		)
		(fp_line
			(start 0.12065 -0.305054)
			(end 0.12065 -0.2794)
			(stroke
				(width 0.1)
				(type default)
			)
			(layer "B.Fab")
		)
		(fp_line
			(start -0.120396 0.3048)
			(end -0.120396 0.2794)
			(stroke
				(width 0.1)
				(type default)
			)
			(layer "B.Fab")
		)
		(fp_line
			(start -0.120396 0.2794)
			(end 0.12065 0.2794)
			(stroke
				(width 0.1)
				(type default)
			)
			(layer "B.Fab")
		)
		(fp_line
			(start -0.12065 -0.2794)
			(end -0.12065 -0.3048)
			(stroke
				(width 0.1)
				(type default)
			)
			(layer "B.Fab")
		)
		(fp_line
			(start -0.12065 -0.3048)
			(end -0.67945 -0.3048)
			(stroke
				(width 0.1)
				(type default)
			)
			(layer "B.Fab")
		)
		(fp_line
			(start -0.67945 0.3048)
			(end -0.120396 0.3048)
			(stroke
				(width 0.1)
				(type default)
			)
			(layer "B.Fab")
		)
		(fp_line
			(start -0.67945 -0.3048)
			(end -0.67945 0.3048)
			(stroke
				(width 0.1)
				(type default)
			)
			(layer "B.Fab")
		)
		(pad "1" smd circle
			(at 0.40005 0)
			(size 0 0)
			(layers "B.Cu" "B.Mask" "B.Paste")
			(net "P3V3_AUX")
		)
		(pad "2" smd circle
			(at -0.40005 0)
			(size 0 0)
			(layers "B.Cu" "B.Mask" "B.Paste")
			(net "PVNN_MAIN_CPU1_VCC")
		)
	)
	(footprint ""
		(layer "B.Cu")
		(at 453.34174 -71.244968 90)
		(property "Reference" "PC71"
			(at 0 0 90)
			(layer "B.SilkS")
			(hide yes)
			(effects
				(font
					(size 1.27 1.27)
				)
				(justify mirror)
			)
		)
		(property "Value" ""
			(at 0 0 90)
			(layer "B.Fab")
			(effects
				(font
					(size 1.27 1.27)
				)
				(justify mirror)
			)
		)
		(duplicate_pad_numbers_are_jumpers no)
		(fp_line
			(start 1.524 -0.762)
			(end -1.524 -0.762)
			(stroke
				(width 0.1524)
				(type default)
			)
			(layer "B.SilkS")
		)
		(fp_line
			(start -1.524 -0.762)
			(end -1.524 0.762)
			(stroke
				(width 0.1524)
				(type default)
			)
			(layer "B.SilkS")
		)
		(fp_line
			(start 1.524 0.762)
			(end 1.524 -0.762)
			(stroke
				(width 0.1524)
				(type default)
			)
			(layer "B.SilkS")
		)
		(fp_line
			(start -1.524 0.762)
			(end 1.524 0.762)
			(stroke
				(width 0.1524)
				(type default)
			)
			(layer "B.SilkS")
		)
		(fp_line
			(start 1.1049 -0.724916)
			(end 1.1049 0.724916)
			(stroke
				(width 0.1)
				(type default)
			)
			(layer "B.Fab")
		)
		(fp_line
			(start -1.1049 -0.724916)
			(end 1.1049 -0.724916)
			(stroke
				(width 0.1)
				(type default)
			)
			(layer "B.Fab")
		)
		(fp_line
			(start 1.1049 0.724916)
			(end -1.1049 0.724916)
			(stroke
				(width 0.1)
				(type default)
			)
			(layer "B.Fab")
		)
		(fp_line
			(start -1.1049 0.724916)
			(end -1.1049 -0.724916)
			(stroke
				(width 0.1)
				(type default)
			)
			(layer "B.Fab")
		)
		(pad "1" smd rect
			(at 0.889 0 90)
			(size 1.016 1.27)
			(layers "B.Cu" "B.Mask" "B.Paste")
			(net "SW_P3V3_AUX_FLT")
		)
		(pad "2" smd rect
			(at -0.889 0 90)
			(size 1.016 1.27)
			(layers "B.Cu" "B.Mask" "B.Paste")
			(net "GND")
		)
	)
	(footprint ""
		(layer "B.Cu")
		(at 368.075972 -184.400952 90)
		(property "Reference" "R967"
			(at 0 0 90)
			(layer "B.SilkS")
			(hide yes)
			(effects
				(font
					(size 1.27 1.27)
				)
				(justify mirror)
			)
		)
		(property "Value" ""
			(at 0 0 90)
			(layer "B.Fab")
			(effects
				(font
					(size 1.27 1.27)
				)
				(justify mirror)
			)
		)
		(duplicate_pad_numbers_are_jumpers no)
		(fp_line
			(start 0.7874 -0.4064)
			(end -0.7874 -0.4064)
			(stroke
				(width 0.1524)
				(type default)
			)
			(layer "B.SilkS")
		)
		(fp_line
			(start -0.7874 -0.4064)
			(end -0.7874 0.4064)
			(stroke
				(width 0.1524)
				(type default)
			)
			(layer "B.SilkS")
		)
		(fp_line
			(start 0.7874 0.4064)
			(end 0.7874 -0.4064)
			(stroke
				(width 0.1524)
				(type default)
			)
			(layer "B.SilkS")
		)
		(fp_line
			(start -0.7874 0.4064)
			(end 0.7874 0.4064)
			(stroke
				(width 0.1524)
				(type default)
			)
			(layer "B.SilkS")
		)
		(fp_line
			(start 0.67945 -0.305054)
			(end 0.12065 -0.305054)
			(stroke
				(width 0.1)
				(type default)
			)
			(layer "B.Fab")
		)
		(fp_line
			(start 0.12065 -0.305054)
			(end 0.12065 -0.2794)
			(stroke
				(width 0.1)
				(type default)
			)
			(layer "B.Fab")
		)
		(fp_line
			(start -0.12065 -0.3048)
			(end -0.67945 -0.3048)
			(stroke
				(width 0.1)
				(type default)
			)
			(layer "B.Fab")
		)
		(fp_line
			(start -0.67945 -0.3048)
			(end -0.67945 0.3048)
			(stroke
				(width 0.1)
				(type default)
			)
			(layer "B.Fab")
		)
		(fp_line
			(start 0.12065 -0.2794)
			(end -0.12065 -0.2794)
			(stroke
				(width 0.1)
				(type default)
			)
			(layer "B.Fab")
		)
		(fp_line
			(start -0.12065 -0.2794)
			(end -0.12065 -0.3048)
			(stroke
				(width 0.1)
				(type default)
			)
			(layer "B.Fab")
		)
		(fp_line
			(start 0.12065 0.2794)
			(end 0.12065 0.3048)
			(stroke
				(width 0.1)
				(type default)
			)
			(layer "B.Fab")
		)
		(fp_line
			(start -0.120396 0.2794)
			(end 0.12065 0.2794)
			(stroke
				(width 0.1)
				(type default)
			)
			(layer "B.Fab")
		)
		(fp_line
			(start 0.67945 0.3048)
			(end 0.67945 -0.305054)
			(stroke
				(width 0.1)
				(type default)
			)
			(layer "B.Fab")
		)
		(fp_line
			(start 0.12065 0.3048)
			(end 0.67945 0.3048)
			(stroke
				(width 0.1)
				(type default)
			)
			(layer "B.Fab")
		)
		(fp_line
			(start -0.120396 0.3048)
			(end -0.120396 0.2794)
			(stroke
				(width 0.1)
				(type default)
			)
			(layer "B.Fab")
		)
		(fp_line
			(start -0.67945 0.3048)
			(end -0.120396 0.3048)
			(stroke
				(width 0.1)
				(type default)
			)
			(layer "B.Fab")
		)
		(pad "1" smd circle
			(at 0.40005 0 270)
			(size 0 0)
			(layers "B.Cu" "B.Mask" "B.Paste")
			(net "P3V3_AUX")
		)
		(pad "2" smd circle
			(at -0.40005 0 270)
			(size 0 0)
			(layers "B.Cu" "B.Mask" "B.Paste")
			(net "SMB_PEHPCPU0_LVC3_SDA")
		)
	)
)
